# S9S_MB_2U (Grand Teton) — schematic netlist excerpt (pin names and nets, part order shuffled) for the footprints in the layout excerpt that follows; sources: Cadence DE-HDL packaged netlist, KiCad conversion of 03242023_DA0F0TMBIJ0_F0T_Motherboard_J_brd_V01_OCP.brd

U334  74LVC1G08W57  74LVC1G08W5-7 IC  pkg SOT25-5_0-95_3X1-6  page 158
  A  = HP_LVC3_OCP_V3_1_PWRGD_R2
  B  = OCP_SFF_AUX_PWR_PLD_EN_R
  GND  = GND
  Y  = OCP_SFF_AUX_PWR_EN_R2
  VCC  = P3V3_AUX

JP16  CONN3_210HP1030BR1  CONN3_210-HP1-030BR1 IO  pkg HEADER1X3XG  page 248
  \1\  = PU_JTAG_SW_PU
  \2\  = JTAG_BMC_SW_OE
  \3\  = GND

(kicad_pcb
	(version 20260206)
	(generator "pcbnew")
	(generator_version "10.0")
	(general
		(thickness 1.6)
		(legacy_teardrops no)
	)
	(paper "A4")
	(title_block
		(title "03242023_DA0F0TMBIJ0_F0T_Motherboard_J_brd_V01_OCP.brd")
		(comment 1 "Grand Teton / footprints 592-593 of 6105")
	)
	(layers
		(0 "F.Cu" signal "TOP")
		(4 "In1.Cu" signal "GND")
		(6 "In2.Cu" signal "IN1")
		(8 "In3.Cu" signal "GND1")
		(10 "In4.Cu" signal "IN2")
		(12 "In5.Cu" signal "GND2")
		(14 "In6.Cu" signal "IN3")
		(16 "In7.Cu" signal "GND3")
		(18 "In8.Cu" signal "VCC")
		(20 "In9.Cu" signal "VCC1")
		(22 "In10.Cu" signal "GND4")
		(24 "In11.Cu" signal "IN4")
		(26 "In12.Cu" signal "GND5")
		(28 "In13.Cu" signal "IN5")
		(30 "In14.Cu" signal "GND6")
		(32 "In15.Cu" signal "IN6")
		(34 "In16.Cu" signal "GND7")
		(2 "B.Cu" signal "BOTTOM")
		(9 "F.Adhes" user "F.Adhesive")
		(11 "B.Adhes" user "B.Adhesive")
		(13 "F.Paste" user "Package Geometry/Pastemask Top")
		(15 "B.Paste" user "Package Geometry/Pastemask Bottom")
		(5 "F.SilkS" user "Ref Des/Silkscreen Top")
		(7 "B.SilkS" user "Ref Des/Silkscreen Bottom")
		(1 "F.Mask" user "Board Geometry/Soldermask Top")
		(3 "B.Mask" user "Board Geometry/Soldermask Bottom")
		(17 "Dwgs.User" user "User.Drawings")
		(19 "Cmts.User" user "User.Comments")
		(21 "Eco1.User" user "User.Eco1")
		(23 "Eco2.User" user "User.Eco2")
		(25 "Edge.Cuts" user "Board Geometry/Outline")
		(27 "Margin" user)
		(31 "F.CrtYd" user "Package Geometry/Place Bound Top")
		(29 "B.CrtYd" user "Package Geometry/Place Bound Bottom")
		(35 "F.Fab" user "Ref Des/Assembly Top")
		(33 "B.Fab" user "Ref Des/Assembly Bottom")
	)
	(footprint ""
		(layer "F.Cu")
		(at 440.358276 -103.340916 90)
		(property "Reference" "U334"
			(at -1.397 -2.225548 90)
			(unlocked yes)
			(layer "F.SilkS")
			(effects
				(font
					(size 0.7874 0.5842)
					(thickness 0.1524)
				)
				(justify left)
			)
		)
		(property "Value" ""
			(at 0 0 90)
			(layer "F.Fab")
			(effects
				(font
					(size 1.27 1.27)
				)
			)
		)
		(duplicate_pad_numbers_are_jumpers no)
		(fp_line
			(start 1.733296 -1.549908)
			(end 0.660908 -1.549908)
			(stroke
				(width 0.1524)
				(type default)
			)
			(layer "F.SilkS")
		)
		(fp_line
			(start 0.660908 -1.549908)
			(end 0 -0.889)
			(stroke
				(width 0.1524)
				(type default)
			)
			(layer "F.SilkS")
		)
		(fp_line
			(start -0.660908 -1.549908)
			(end -1.733296 -1.549908)
			(stroke
				(width 0.1524)
				(type default)
			)
			(layer "F.SilkS")
		)
		(fp_line
			(start -1.733296 -1.549908)
			(end -1.733296 1.549908)
			(stroke
				(width 0.1524)
				(type default)
			)
			(layer "F.SilkS")
		)
		(fp_line
			(start 0 -0.889)
			(end -0.660908 -1.549908)
			(stroke
				(width 0.1524)
				(type default)
			)
			(layer "F.SilkS")
		)
		(fp_line
			(start 1.733296 1.549908)
			(end 1.733296 -1.549908)
			(stroke
				(width 0.1524)
				(type default)
			)
			(layer "F.SilkS")
		)
		(fp_line
			(start -1.733296 1.549908)
			(end 1.733296 1.549908)
			(stroke
				(width 0.1524)
				(type default)
			)
			(layer "F.SilkS")
		)
		(fp_poly
			(pts
				(xy -2.10693 -2.095246) (xy -2.46634 -1.73609) (xy -1.927352 -1.556512)
			)
			(stroke
				(width 0)
				(type default)
			)
			(fill yes)
			(layer "F.SilkS")
		)
		(fp_line
			(start 0.849884 -1.549908)
			(end -0.849884 -1.549908)
			(stroke
				(width 0.1)
				(type default)
			)
			(layer "F.Fab")
		)
		(fp_line
			(start -0.849884 -1.549908)
			(end -0.849884 1.549908)
			(stroke
				(width 0.1)
				(type default)
			)
			(layer "F.Fab")
		)
		(fp_line
			(start 0.849884 1.549908)
			(end 0.849884 -1.549908)
			(stroke
				(width 0.1)
				(type default)
			)
			(layer "F.Fab")
		)
		(fp_line
			(start -0.849884 1.549908)
			(end 0.849884 1.549908)
			(stroke
				(width 0.1)
				(type default)
			)
			(layer "F.Fab")
		)
		(fp_poly
			(pts
				(xy -2.4384 -1.20396) (xy -2.4384 -0.69596) (xy -1.9304 -0.94996)
			)
			(stroke
				(width 0)
				(type default)
			)
			(fill yes)
			(layer "F.Fab")
		)
		(pad "1" smd rect
			(at -1.199896 -0.94996)
			(size 0.5588 0.8128)
			(layers "F.Cu" "F.Mask" "F.Paste")
			(net "HP_LVC3_OCP_V3_1_PWRGD_R2")
		)
		(pad "2" smd rect
			(at -1.199896 0)
			(size 0.5588 0.8128)
			(layers "F.Cu" "F.Mask" "F.Paste")
			(net "OCP_SFF_AUX_PWR_PLD_EN_R")
		)
		(pad "3" smd rect
			(at -1.199896 0.94996)
			(size 0.5588 0.8128)
			(layers "F.Cu" "F.Mask" "F.Paste")
			(net "GND")
		)
		(pad "4" smd rect
			(at 1.199896 0.94996)
			(size 0.5588 0.8128)
			(layers "F.Cu" "F.Mask" "F.Paste")
			(net "OCP_SFF_AUX_PWR_EN_R2")
		)
		(pad "5" smd rect
			(at 1.199896 -0.94996)
			(size 0.5588 0.8128)
			(layers "F.Cu" "F.Mask" "F.Paste")
			(net "P3V3_AUX")
		)
	)
	(footprint ""
		(layer "F.Cu")
		(at 120.269 -62.575948 90)
		(property "Reference" "JP16"
			(at -0.02667 6.985 0)
			(unlocked yes)
			(layer "F.SilkS")
			(effects
				(font
					(size 0.7874 0.5842)
					(thickness 0.1524)
				)
				(justify left)
			)
		)
		(property "Value" ""
			(at 0 0 90)
			(layer "F.Fab")
			(effects
				(font
					(size 1.27 1.27)
				)
			)
		)
		(duplicate_pad_numbers_are_jumpers no)
		(fp_line
			(start 1.249934 -1.320038)
			(end 1.249934 6.400038)
			(stroke
				(width 0.1524)
				(type default)
			)
			(layer "F.SilkS")
		)
		(fp_line
			(start -1.249934 -1.320038)
			(end 1.249934 -1.320038)
			(stroke
				(width 0.1524)
				(type default)
			)
			(layer "F.SilkS")
		)
		(fp_line
			(start 1.249934 6.400038)
			(end -1.249934 6.400038)
			(stroke
				(width 0.1524)
				(type default)
			)
			(layer "F.SilkS")
		)
		(fp_line
			(start -1.249934 6.400038)
			(end -1.249934 -1.320038)
			(stroke
				(width 0.1524)
				(type default)
			)
			(layer "F.SilkS")
		)
		(fp_poly
			(pts
				(xy -2.156206 -2.266442) (xy -1.72339 -1.09982) (xy -2.916428 -1.453642)
			)
			(stroke
				(width 0)
				(type default)
			)
			(fill yes)
			(layer "F.SilkS")
		)
		(fp_line
			(start 1.249934 -1.320038)
			(end 1.249934 6.400038)
			(stroke
				(width 0.1)
				(type default)
			)
			(layer "F.Fab")
		)
		(fp_line
			(start -1.249934 -1.320038)
			(end 1.249934 -1.320038)
			(stroke
				(width 0.1)
				(type default)
			)
			(layer "F.Fab")
		)
		(fp_line
			(start 1.249934 6.400038)
			(end -1.249934 6.400038)
			(stroke
				(width 0.1)
				(type default)
			)
			(layer "F.Fab")
		)
		(fp_line
			(start -1.249934 6.400038)
			(end -1.249934 -1.320038)
			(stroke
				(width 0.1)
				(type default)
			)
			(layer "F.Fab")
		)
		(fp_poly
			(pts
				(xy -2.5654 -0.556514) (xy -1.452372 0) (xy -2.5654 0.556514)
			)
			(stroke
				(width 0)
				(type default)
			)
			(fill yes)
			(layer "F.Fab")
		)
		(fp_text user "3"
			(at -1.778 5.13207 90)
			(unlocked yes)
			(layer "F.SilkS")
			(effects
				(font
					(size 0.7874 0.5842)
					(thickness 0.1524)
				)
			)
		)
		(fp_text user "1"
			(at -1.143 0.02667 90)
			(unlocked yes)
			(layer "B.SilkS")
			(effects
				(font
					(size 0.7874 0.5842)
					(thickness 0.1524)
				)
				(justify mirror)
			)
		)
		(fp_text user "3"
			(at -1.1557 5.18287 90)
			(unlocked yes)
			(layer "B.SilkS")
			(effects
				(font
					(size 0.7874 0.5842)
					(thickness 0.1524)
				)
				(justify mirror)
			)
		)
		(fp_text user "1"
			(at -1.143 0.02667 90)
			(unlocked yes)
			(layer "B.Fab")
			(effects
				(font
					(size 0.7874 0.5842)
					(thickness 0.1524)
				)
				(justify mirror)
			)
		)
		(fp_text user "3"
			(at -1.1557 5.18287 90)
			(unlocked yes)
			(layer "B.Fab")
			(effects
				(font
					(size 0.7874 0.5842)
					(thickness 0.1524)
				)
				(justify mirror)
			)
		)
		(fp_text user "3"
			(at -1.778 5.13207 90)
			(unlocked yes)
			(layer "F.Fab")
			(effects
				(font
					(size 0.7874 0.5842)
					(thickness 0.1524)
				)
			)
		)
		(pad "1" thru_hole rect
			(at 0 0 90)
			(size 1.5494 1.5494)
			(drill 1.0414)
			(layers "*.Cu" "*.Mask")
			(remove_unused_layers no)
			(net "PU_JTAG_SW_PU")
			(clearance 0)
			(padstack
				(mode front_inner_back)
				(layer "Inner"
					(shape circle)
					(size 1.5494 1.5494)
					(clearance 0)
				)
				(layer "B.Cu"
					(shape rect)
					(size 1.5494 1.5494)
					(clearance 0)
				)
			)
		)
		(pad "2" thru_hole circle
			(at 0 2.54 90)
			(size 1.5494 1.5494)
			(drill 1.0414)
			(layers "*.Cu" "*.Mask")
			(remove_unused_layers no)
			(net "JTAG_BMC_SW_OE")
			(clearance 0)
		)
		(pad "3" thru_hole circle
			(at 0 5.08 90)
			(size 1.5494 1.5494)
			(drill 1.0414)
			(layers "*.Cu" "*.Mask")
			(remove_unused_layers no)
			(net "GND")
			(clearance 0)
		)
	)
)
